FILE_TYPE = CONNECTIVITY;
{Allegro Design Entry HDL 17.4-2019 S026 (4007227) 1/17/2022}
"PAGE_NUMBER" = 139;
0"NC";
END.
